(kicad_pcb
	(version 20240108)
	(generator "pcbnew")
	(generator_version "8.0")
	(general
		(thickness 1.62)
		(legacy_teardrops no)
	)
	(paper "A4")
	(title_block
		(title "Jetson Orin Baseboard")
		(date "2025-03-12")
		(rev "1.3.4")
		(company "Antmicro Ltd")
		(comment 1 "www.antmicro.com")
		(comment 9 "footprint 59 of 677 (J15), pads 1-85 of 264")
	)
	(layers
		(0 "F.Cu" signal)
		(1 "In1.Cu" signal)
		(2 "In2.Cu" signal)
		(3 "In3.Cu" signal)
		(4 "In4.Cu" jumper)
		(5 "In5.Cu" signal)
		(6 "In6.Cu" signal)
		(31 "B.Cu" signal)
		(32 "B.Adhes" user "B.Adhesive")
		(33 "F.Adhes" user "F.Adhesive")
		(34 "B.Paste" user)
		(35 "F.Paste" user)
		(36 "B.SilkS" user "B.Silkscreen")
		(37 "F.SilkS" user "F.Silkscreen")
		(38 "B.Mask" user)
		(39 "F.Mask" user)
		(40 "Dwgs.User" user "User.Drawings")
		(41 "Cmts.User" user "User.Comments")
		(42 "Eco1.User" user "User.Eco1")
		(43 "Eco2.User" user "User.Eco2")
		(44 "Edge.Cuts" user)
		(45 "Margin" user)
		(46 "B.CrtYd" user "B.Courtyard")
		(47 "F.CrtYd" user "F.Courtyard")
		(48 "B.Fab" user)
		(49 "F.Fab" user)
	)
	(footprint "antmicro-footprints:TE_2309413"
		(locked yes)
		(layer "F.Cu")
		(at 92.706 84.0225)
		(descr "260 pin DDR4 SODIMM Right Angle Socket, 9.2 mm (0.362 in) Stack Height, https://www.te.com/global-en/product-2309413-1.html")
		(tags "ddr4 sodimm right angle 9.2mm height jetson som")
		(property "Reference" "J15"
			(at -36.75 -13.25 0)
			(layer "F.SilkS")
			(effects
				(font
					(size 0.7 0.7)
					(thickness 0.15)
				)
				(justify left bottom)
			)
		)
		(property "Value" "Bus_DDR4_SODIMM_CUSTOM_Jetson-Orin-H9.2mm-socket"
			(at -38 14.25 0)
			(layer "F.Fab")
			(effects
				(font
					(size 0.7 0.7)
					(thickness 0.15)
				)
				(justify left bottom)
			)
		)
		(property "Footprint" "antmicro-footprints:TE_2309413"
			(at 0 0 0)
			(layer "F.Fab")
			(hide yes)
			(effects
				(font
					(size 1.27 1.27)
					(thickness 0.15)
				)
			)
		)
		(property "Datasheet" "https://developer.nvidia.com/jetson-orin-nx-series-data-sheet"
			(at 0 0 0)
			(layer "F.Fab")
			(hide yes)
			(effects
				(font
					(size 1.27 1.27)
					(thickness 0.15)
				)
			)
		)
		(property "Author" "Antmicro"
			(at 0 0 0)
			(layer "F.Fab")
			(hide yes)
			(effects
				(font
					(size 1 1)
					(thickness 0.15)
				)
			)
		)
		(property "License" "Apache-2.0"
			(at 0 0 0)
			(layer "F.Fab")
			(hide yes)
			(effects
				(font
					(size 1 1)
					(thickness 0.15)
				)
			)
		)
		(property "MPN" "2309413-1"
			(at 0 0 0)
			(layer "F.Fab")
			(hide yes)
			(effects
				(font
					(size 1 1)
					(thickness 0.15)
				)
			)
		)
		(property "Manufacturer" "TE Connectivity"
			(at 0 0 0)
			(layer "F.Fab")
			(hide yes)
			(effects
				(font
					(size 1 1)
					(thickness 0.15)
				)
			)
		)
		(sheetname "SoM")
		(sheetfile "som.kicad_sch")
		(attr smd)
		(pad "" np_thru_hole circle
			(at -34.406 -7.926)
			(size 1.15 1.15)
			(drill 1.15)
			(layers "*.Cu" "*.Mask")
		)
		(pad "" np_thru_hole circle
			(at 34.395 -7.926)
			(size 1.65 1.65)
			(drill 1.65)
			(layers "*.Cu" "*.Mask")
		)
		(pad "1" smd rect
			(at 33.369 -12.026 90)
			(size 1.75 0.3)
			(layers "F.Cu" "F.Paste" "F.Mask")
			(net 1 "GND")
			(pinfunction "GND")
			(pintype "passive")
		)
		(pad "2" smd rect
			(at 33.119 -3.826 90)
			(size 1.75 0.3)
			(layers "F.Cu" "F.Paste" "F.Mask")
			(net 1 "GND")
			(pinfunction "GND")
			(pintype "passive")
		)
		(pad "3" smd rect
			(at 32.869 -12.026 90)
			(size 1.75 0.3)
			(layers "F.Cu" "F.Paste" "F.Mask")
			(net 2 "CSI1_D0_N")
			(pinfunction "CSI1_D0_N")
			(pintype "passive")
		)
		(pad "4" smd rect
			(at 32.619 -3.826 90)
			(size 1.75 0.3)
			(layers "F.Cu" "F.Paste" "F.Mask")
			(net 3 "CSI0_D0_N")
			(pinfunction "CSI0_D0_N")
			(pintype "passive")
		)
		(pad "5" smd rect
			(at 32.369 -12.026 90)
			(size 1.75 0.3)
			(layers "F.Cu" "F.Paste" "F.Mask")
			(net 4 "CSI1_D0_P")
			(pinfunction "CSI1_D0_P")
			(pintype "passive")
		)
		(pad "6" smd rect
			(at 32.119 -3.826 90)
			(size 1.75 0.3)
			(layers "F.Cu" "F.Paste" "F.Mask")
			(net 5 "CSI0_D0_P")
			(pinfunction "CSI0_D0_P")
			(pintype "passive")
		)
		(pad "7" smd rect
			(at 31.87 -12.026 90)
			(size 1.75 0.3)
			(layers "F.Cu" "F.Paste" "F.Mask")
			(net 1 "GND")
			(pinfunction "GND")
			(pintype "passive")
		)
		(pad "8" smd rect
			(at 31.62 -3.826 90)
			(size 1.75 0.3)
			(layers "F.Cu" "F.Paste" "F.Mask")
			(net 1 "GND")
			(pinfunction "GND")
			(pintype "passive")
		)
		(pad "9" smd rect
			(at 31.37 -12.026 90)
			(size 1.75 0.3)
			(layers "F.Cu" "F.Paste" "F.Mask")
			(net 6 "CSI1_CLK_N")
			(pinfunction "CSI1_CLK_N")
			(pintype "passive")
		)
		(pad "10" smd rect
			(at 31.12 -3.826 90)
			(size 1.75 0.3)
			(layers "F.Cu" "F.Paste" "F.Mask")
			(net 7 "CSI0_CLK_N")
			(pinfunction "CSI0_CLK_N")
			(pintype "passive")
		)
		(pad "11" smd rect
			(at 30.87 -12.026 90)
			(size 1.75 0.3)
			(layers "F.Cu" "F.Paste" "F.Mask")
			(net 8 "CSI1_CLK_P")
			(pinfunction "CSI1_CLK_P")
			(pintype "passive")
		)
		(pad "12" smd rect
			(at 30.62 -3.826 90)
			(size 1.75 0.3)
			(layers "F.Cu" "F.Paste" "F.Mask")
			(net 9 "CSI0_CLK_P")
			(pinfunction "CSI0_CLK_P")
			(pintype "passive")
		)
		(pad "13" smd rect
			(at 30.37 -12.026 90)
			(size 1.75 0.3)
			(layers "F.Cu" "F.Paste" "F.Mask")
			(net 1 "GND")
			(pinfunction "GND")
			(pintype "passive")
		)
		(pad "14" smd rect
			(at 30.12 -3.826 90)
			(size 1.75 0.3)
			(layers "F.Cu" "F.Paste" "F.Mask")
			(net 1 "GND")
			(pinfunction "GND")
			(pintype "passive")
		)
		(pad "15" smd rect
			(at 29.87 -12.026 90)
			(size 1.75 0.3)
			(layers "F.Cu" "F.Paste" "F.Mask")
			(net 10 "CSI1_D1_N")
			(pinfunction "CSI1_D1_N")
			(pintype "passive")
		)
		(pad "16" smd rect
			(at 29.62 -3.826 90)
			(size 1.75 0.3)
			(layers "F.Cu" "F.Paste" "F.Mask")
			(net 11 "CSI0_D1_N")
			(pinfunction "CSI0_D1_N")
			(pintype "passive")
		)
		(pad "17" smd rect
			(at 29.37 -12.026 90)
			(size 1.75 0.3)
			(layers "F.Cu" "F.Paste" "F.Mask")
			(net 12 "CSI1_D1_P")
			(pinfunction "CSI1_D1_P")
			(pintype "passive")
		)
		(pad "18" smd rect
			(at 29.12 -3.826 90)
			(size 1.75 0.3)
			(layers "F.Cu" "F.Paste" "F.Mask")
			(net 13 "CSI0_D1_P")
			(pinfunction "CSI0_D1_P")
			(pintype "passive")
		)
		(pad "19" smd rect
			(at 28.87 -12.026 90)
			(size 1.75 0.3)
			(layers "F.Cu" "F.Paste" "F.Mask")
			(net 1 "GND")
			(pinfunction "GND")
			(pintype "passive")
		)
		(pad "20" smd rect
			(at 28.62 -3.826 90)
			(size 1.75 0.3)
			(layers "F.Cu" "F.Paste" "F.Mask")
			(net 1 "GND")
			(pinfunction "GND")
			(pintype "passive")
		)
		(pad "21" smd rect
			(at 28.37 -12.026 90)
			(size 1.75 0.3)
			(layers "F.Cu" "F.Paste" "F.Mask")
			(net 14 "CSI3_D0_N")
			(pinfunction "CSI3_D0_N")
			(pintype "passive")
		)
		(pad "22" smd rect
			(at 28.12 -3.826 90)
			(size 1.75 0.3)
			(layers "F.Cu" "F.Paste" "F.Mask")
			(net 15 "CSI2_D0_N")
			(pinfunction "CSI2_D0_N")
			(pintype "passive")
		)
		(pad "23" smd rect
			(at 27.87 -12.026 90)
			(size 1.75 0.3)
			(layers "F.Cu" "F.Paste" "F.Mask")
			(net 16 "CSI3_D0_P")
			(pinfunction "CSI3_D0_P")
			(pintype "passive")
		)
		(pad "24" smd rect
			(at 27.62 -3.826 90)
			(size 1.75 0.3)
			(layers "F.Cu" "F.Paste" "F.Mask")
			(net 17 "CSI2_D0_P")
			(pinfunction "CSI2_D0_P")
			(pintype "passive")
		)
		(pad "25" smd rect
			(at 27.37 -12.026 90)
			(size 1.75 0.3)
			(layers "F.Cu" "F.Paste" "F.Mask")
			(net 1 "GND")
			(pinfunction "GND")
			(pintype "passive")
		)
		(pad "26" smd rect
			(at 27.12 -3.826 90)
			(size 1.75 0.3)
			(layers "F.Cu" "F.Paste" "F.Mask")
			(net 1 "GND")
			(pinfunction "GND")
			(pintype "passive")
		)
		(pad "27" smd rect
			(at 26.87 -12.026 90)
			(size 1.75 0.3)
			(layers "F.Cu" "F.Paste" "F.Mask")
			(net 18 "CSI3_CLK_N")
			(pinfunction "CSI3_CLK_N")
			(pintype "passive")
		)
		(pad "28" smd rect
			(at 26.62 -3.826 90)
			(size 1.75 0.3)
			(layers "F.Cu" "F.Paste" "F.Mask")
			(net 19 "CSI2_CLK_N")
			(pinfunction "CSI2_CLK_N")
			(pintype "passive")
		)
		(pad "29" smd rect
			(at 26.37 -12.026 90)
			(size 1.75 0.3)
			(layers "F.Cu" "F.Paste" "F.Mask")
			(net 20 "CSI3_CLK_P")
			(pinfunction "CSI3_CLK_P")
			(pintype "passive")
		)
		(pad "30" smd rect
			(at 26.12 -3.826 90)
			(size 1.75 0.3)
			(layers "F.Cu" "F.Paste" "F.Mask")
			(net 21 "CSI2_CLK_P")
			(pinfunction "CSI2_CLK_P")
			(pintype "passive")
		)
		(pad "31" smd rect
			(at 25.87 -12.026 90)
			(size 1.75 0.3)
			(layers "F.Cu" "F.Paste" "F.Mask")
			(net 1 "GND")
			(pinfunction "GND")
			(pintype "passive")
		)
		(pad "32" smd rect
			(at 25.62 -3.826 90)
			(size 1.75 0.3)
			(layers "F.Cu" "F.Paste" "F.Mask")
			(net 1 "GND")
			(pinfunction "GND")
			(pintype "passive")
		)
		(pad "33" smd rect
			(at 25.37 -12.026 90)
			(size 1.75 0.3)
			(layers "F.Cu" "F.Paste" "F.Mask")
			(net 22 "CSI3_D1_N")
			(pinfunction "CSI3_D1_N")
			(pintype "passive")
		)
		(pad "34" smd rect
			(at 25.12 -3.826 90)
			(size 1.75 0.3)
			(layers "F.Cu" "F.Paste" "F.Mask")
			(net 23 "CSI2_D1_N")
			(pinfunction "CSI2_D1_N")
			(pintype "passive")
		)
		(pad "35" smd rect
			(at 24.87 -12.026 90)
			(size 1.75 0.3)
			(layers "F.Cu" "F.Paste" "F.Mask")
			(net 24 "CSI3_D1_P")
			(pinfunction "CSI3_D1_P")
			(pintype "passive")
		)
		(pad "36" smd rect
			(at 24.62 -3.826 90)
			(size 1.75 0.3)
			(layers "F.Cu" "F.Paste" "F.Mask")
			(net 25 "CSI2_D1_P")
			(pinfunction "CSI2_D1_P")
			(pintype "passive")
		)
		(pad "37" smd rect
			(at 24.37 -12.026 90)
			(size 1.75 0.3)
			(layers "F.Cu" "F.Paste" "F.Mask")
			(net 1 "GND")
			(pinfunction "GND")
			(pintype "passive")
		)
		(pad "38" smd rect
			(at 24.12 -3.826 90)
			(size 1.75 0.3)
			(layers "F.Cu" "F.Paste" "F.Mask")
			(net 1 "GND")
			(pinfunction "GND")
			(pintype "passive")
		)
		(pad "39" smd rect
			(at 23.87 -12.026 90)
			(size 1.75 0.3)
			(layers "F.Cu" "F.Paste" "F.Mask")
			(net 107 "USBSS1_RX_N")
			(pinfunction "USBSS1_RX_N")
			(pintype "passive")
		)
		(pad "40" smd rect
			(at 23.62 -3.826 90)
			(size 1.75 0.3)
			(layers "F.Cu" "F.Paste" "F.Mask")
			(net 113 "PCIE2_RX0_N")
			(pinfunction "PCIE2_RX0_N")
			(pintype "passive")
		)
		(pad "41" smd rect
			(at 23.37 -12.026 90)
			(size 1.75 0.3)
			(layers "F.Cu" "F.Paste" "F.Mask")
			(net 114 "USBSS1_RX_P")
			(pinfunction "USBSS1_RX_P")
			(pintype "passive")
		)
		(pad "42" smd rect
			(at 23.12 -3.826 90)
			(size 1.75 0.3)
			(layers "F.Cu" "F.Paste" "F.Mask")
			(net 131 "PCIE2_RX0_P")
			(pinfunction "PCIE2_RX0_P")
			(pintype "passive")
		)
		(pad "43" smd rect
			(at 22.87 -12.026 90)
			(size 1.75 0.3)
			(layers "F.Cu" "F.Paste" "F.Mask")
			(net 1 "GND")
			(pinfunction "GND")
			(pintype "passive")
		)
		(pad "44" smd rect
			(at 22.62 -3.826 90)
			(size 1.75 0.3)
			(layers "F.Cu" "F.Paste" "F.Mask")
			(net 1 "GND")
			(pinfunction "GND")
			(pintype "passive")
		)
		(pad "45" smd rect
			(at 22.37 -12.026 90)
			(size 1.75 0.3)
			(layers "F.Cu" "F.Paste" "F.Mask")
			(net 132 "USBSS1_TX_N")
			(pinfunction "USBSS1_TX_N")
			(pintype "passive")
		)
		(pad "46" smd rect
			(at 22.12 -3.826 90)
			(size 1.75 0.3)
			(layers "F.Cu" "F.Paste" "F.Mask")
			(net 156 "PCIE2_TX0_N")
			(pinfunction "PCIE2_TX0_N")
			(pintype "passive")
		)
		(pad "47" smd rect
			(at 21.87 -12.026 90)
			(size 1.75 0.3)
			(layers "F.Cu" "F.Paste" "F.Mask")
			(net 157 "USBSS1_TX_P")
			(pinfunction "USBSS1_TX_P")
			(pintype "passive")
		)
		(pad "48" smd rect
			(at 21.62 -3.826 90)
			(size 1.75 0.3)
			(layers "F.Cu" "F.Paste" "F.Mask")
			(net 158 "PCIE2_TX0_P")
			(pinfunction "PCIE2_TX0_P")
			(pintype "passive")
		)
		(pad "49" smd rect
			(at 21.37 -12.026 90)
			(size 1.75 0.3)
			(layers "F.Cu" "F.Paste" "F.Mask")
			(net 1 "GND")
			(pinfunction "GND")
			(pintype "passive")
		)
		(pad "50" smd rect
			(at 21.12 -3.826 90)
			(size 1.75 0.3)
			(layers "F.Cu" "F.Paste" "F.Mask")
			(net 1 "GND")
			(pinfunction "GND")
			(pintype "passive")
		)
		(pad "51" smd rect
			(at 20.87 -12.026 90)
			(size 1.75 0.3)
			(layers "F.Cu" "F.Paste" "F.Mask")
			(net 159 "USBSS2_RX_N")
			(pinfunction "USBSS2_RX_N")
			(pintype "passive")
		)
		(pad "52" smd rect
			(at 20.62 -3.826 90)
			(size 1.75 0.3)
			(layers "F.Cu" "F.Paste" "F.Mask")
			(net 163 "PCIE2_CLK_N")
			(pinfunction "PCIE2_CLK_N")
			(pintype "passive")
		)
		(pad "53" smd rect
			(at 20.37 -12.026 90)
			(size 1.75 0.3)
			(layers "F.Cu" "F.Paste" "F.Mask")
			(net 165 "USBSS2_RX_P")
			(pinfunction "USBSS2_RX_P")
			(pintype "passive")
		)
		(pad "54" smd rect
			(at 20.12 -3.826 90)
			(size 1.75 0.3)
			(layers "F.Cu" "F.Paste" "F.Mask")
			(net 166 "PCIE2_CLK_P")
			(pinfunction "PCIE2_CLK_P")
			(pintype "passive")
		)
		(pad "55" smd rect
			(at 19.87 -12.026 90)
			(size 1.75 0.3)
			(layers "F.Cu" "F.Paste" "F.Mask")
			(net 1 "GND")
			(pinfunction "GND")
			(pintype "passive")
		)
		(pad "56" smd rect
			(at 19.62 -3.826 90)
			(size 1.75 0.3)
			(layers "F.Cu" "F.Paste" "F.Mask")
			(net 1 "GND")
			(pinfunction "GND")
			(pintype "passive")
		)
		(pad "57" smd rect
			(at 19.37 -12.026 90)
			(size 1.75 0.3)
			(layers "F.Cu" "F.Paste" "F.Mask")
			(net 167 "USBSS2_TX_N")
			(pinfunction "USBSS2_TX_N")
			(pintype "passive")
		)
		(pad "58" smd rect
			(at 19.12 -3.826 90)
			(size 1.75 0.3)
			(layers "F.Cu" "F.Paste" "F.Mask")
			(net 172 "PCIE2_RX1_N")
			(pinfunction "PCIE3_RX0_N")
			(pintype "passive")
		)
		(pad "59" smd rect
			(at 18.87 -12.026 90)
			(size 1.75 0.3)
			(layers "F.Cu" "F.Paste" "F.Mask")
			(net 173 "USBSS2_TX_P")
			(pinfunction "USBSS2_TX_P")
			(pintype "passive")
		)
		(pad "60" smd rect
			(at 18.62 -3.826 90)
			(size 1.75 0.3)
			(layers "F.Cu" "F.Paste" "F.Mask")
			(net 175 "PCIE2_RX1_P")
			(pinfunction "PCIE3_RX0_P")
			(pintype "passive")
		)
		(pad "61" smd rect
			(at 18.37 -12.026 90)
			(size 1.75 0.3)
			(layers "F.Cu" "F.Paste" "F.Mask")
			(net 1 "GND")
			(pinfunction "GND")
			(pintype "passive")
		)
		(pad "62" smd rect
			(at 18.12 -3.826 90)
			(size 1.75 0.3)
			(layers "F.Cu" "F.Paste" "F.Mask")
			(net 1 "GND")
			(pinfunction "GND")
			(pintype "passive")
		)
		(pad "63" smd rect
			(at 17.87 -12.026 90)
			(size 1.75 0.3)
			(layers "F.Cu" "F.Paste" "F.Mask")
			(net 274 "DP1_TXD0_HDMI_TX2_N")
			(pinfunction "DP1_TXD0_N")
			(pintype "passive")
		)
		(pad "64" smd rect
			(at 17.62 -3.826 90)
			(size 1.75 0.3)
			(layers "F.Cu" "F.Paste" "F.Mask")
			(net 357 "PCIE2_TX1_N")
			(pinfunction "PCIE3_TX0_N")
			(pintype "passive")
		)
		(pad "65" smd rect
			(at 17.37 -12.026 90)
			(size 1.75 0.3)
			(layers "F.Cu" "F.Paste" "F.Mask")
			(net 367 "DP1_TXD0_HDMI_TX2_P")
			(pinfunction "DP1_TXD0_P")
			(pintype "passive")
		)
		(pad "66" smd rect
			(at 17.12 -3.826 90)
			(size 1.75 0.3)
			(layers "F.Cu" "F.Paste" "F.Mask")
			(net 370 "PCIE2_TX1_P")
			(pinfunction "PCIE3_TX0_P")
			(pintype "passive")
		)
		(pad "67" smd rect
			(at 16.87 -12.026 90)
			(size 1.75 0.3)
			(layers "F.Cu" "F.Paste" "F.Mask")
			(net 1 "GND")
			(pinfunction "GND")
			(pintype "passive")
		)
		(pad "68" smd rect
			(at 16.62 -3.826 90)
			(size 1.75 0.3)
			(layers "F.Cu" "F.Paste" "F.Mask")
			(net 1 "GND")
			(pinfunction "GND")
			(pintype "passive")
		)
		(pad "69" smd rect
			(at 16.37 -12.026 90)
			(size 1.75 0.3)
			(layers "F.Cu" "F.Paste" "F.Mask")
			(net 375 "DP1_TXD1_HDMI_TX1_N")
			(pinfunction "DP1_TXD1_N")
			(pintype "passive")
		)
		(pad "70" smd rect
			(at 16.12 -3.826 90)
			(size 1.75 0.3)
			(layers "F.Cu" "F.Paste" "F.Mask")
			(net 733 "unconnected-(J15B-DSI_D0_N-Pad70)")
			(pinfunction "DSI_D0_N")
			(pintype "passive+no_connect")
		)
		(pad "71" smd rect
			(at 15.87 -12.026 90)
			(size 1.75 0.3)
			(layers "F.Cu" "F.Paste" "F.Mask")
			(net 417 "DP1_TXD1_HDMI_TX1_P")
			(pinfunction "DP1_TXD1_P")
			(pintype "passive")
		)
		(pad "72" smd rect
			(at 15.62 -3.826 90)
			(size 1.75 0.3)
			(layers "F.Cu" "F.Paste" "F.Mask")
			(net 734 "unconnected-(J15B-DSI_D0_P-Pad72)")
			(pinfunction "DSI_D0_P")
			(pintype "passive+no_connect")
		)
		(pad "73" smd rect
			(at 15.37 -12.026 90)
			(size 1.75 0.3)
			(layers "F.Cu" "F.Paste" "F.Mask")
			(net 1 "GND")
			(pinfunction "GND")
			(pintype "passive")
		)
		(pad "74" smd rect
			(at 15.12 -3.826 90)
			(size 1.75 0.3)
			(layers "F.Cu" "F.Paste" "F.Mask")
			(net 1 "GND")
			(pinfunction "GND")
			(pintype "passive")
		)
		(pad "75" smd rect
			(at 14.87 -12.026 90)
			(size 1.75 0.3)
			(layers "F.Cu" "F.Paste" "F.Mask")
			(net 418 "DP1_TXD2_HDMI_TX0_N")
			(pinfunction "DP1_TXD2_N")
			(pintype "passive")
		)
		(pad "76" smd rect
			(at 14.62 -3.826 90)
			(size 1.75 0.3)
			(layers "F.Cu" "F.Paste" "F.Mask")
			(net 735 "unconnected-(J15B-DSI_CLK_N-Pad76)")
			(pinfunction "DSI_CLK_N")
			(pintype "passive+no_connect")
		)
		(pad "77" smd rect
			(at 14.37 -12.026 90)
			(size 1.75 0.3)
			(layers "F.Cu" "F.Paste" "F.Mask")
			(net 419 "DP1_TXD2_HDMI_TX0_P")
			(pinfunction "DP1_TXD2_P")
			(pintype "passive")
		)
		(pad "78" smd rect
			(at 14.12 -3.826 90)
			(size 1.75 0.3)
			(layers "F.Cu" "F.Paste" "F.Mask")
			(net 736 "unconnected-(J15B-DSI_CLK_P-Pad78)")
			(pinfunction "DSI_CLK_P")
			(pintype "passive+no_connect")
		)
		(pad "79" smd rect
			(at 13.87 -12.026 90)
			(size 1.75 0.3)
			(layers "F.Cu" "F.Paste" "F.Mask")
			(net 1 "GND")
			(pinfunction "GND")
			(pintype "passive")
		)
		(pad "80" smd rect
			(at 13.62 -3.826 90)
			(size 1.75 0.3)
			(layers "F.Cu" "F.Paste" "F.Mask")
			(net 1 "GND")
			(pinfunction "GND")
			(pintype "passive")
		)
		(pad "81" smd rect
			(at 13.37 -12.026 90)
			(size 1.75 0.3)
			(layers "F.Cu" "F.Paste" "F.Mask")
			(net 420 "DP1_TXD3_HDMI_TXC_N")
			(pinfunction "DP1_TXD3_N")
			(pintype "passive")
		)
		(pad "82" smd rect
			(at 13.12 -3.826 90)
			(size 1.75 0.3)
			(layers "F.Cu" "F.Paste" "F.Mask")
			(net 737 "unconnected-(J15B-DSI_D1_N-Pad82)")
			(pinfunction "DSI_D1_N")
			(pintype "passive+no_connect")
		)
		(pad "83" smd rect
			(at 12.87 -12.026 90)
			(size 1.75 0.3)
			(layers "F.Cu" "F.Paste" "F.Mask")
			(net 422 "DP1_TXD3_HDMI_TXC_P")
			(pinfunction "DP1_TXD3_P")
			(pintype "passive")
		)
	)
)
